# T6G (Grand Teton) — schematic netlist excerpt (pin names and nets, part order shuffled) for the footprints in the layout excerpt that follows; sources: Cadence DE-HDL packaged netlist, KiCad conversion of 04192023_DAF0TMB3IC0_F0TG_MB_C_brd_V02_OCP.brd

R3298  Q_RES  10K 1% CHIP  pkg 0402LF  page 144 : A = P3V3_AUX ; B = HDD_ACTIVITY_BUF_N
R3171  Q_RES  0 5% CHIP  pkg 0402LF  page 137 : A = OCP_V3_2_ISO_BIF2_EN ; B = OCP_V3_2_BIF2_R_N

(kicad_pcb
	(version 20260206)
	(generator "pcbnew")
	(generator_version "10.0")
	(general
		(thickness 1.6)
		(legacy_teardrops no)
	)
	(paper "A4")
	(title_block
		(title "04192023_DAF0TMB3IC0_F0TG_MB_C_brd_V02_OCP.brd")
		(comment 1 "Grand Teton / footprints 3073-3074 of 8354")
	)
	(layers
		(0 "F.Cu" signal "TOP")
		(4 "In1.Cu" signal "GND")
		(6 "In2.Cu" signal "IN1")
		(8 "In3.Cu" signal "GND1")
		(10 "In4.Cu" signal "IN2")
		(12 "In5.Cu" signal "GND2")
		(14 "In6.Cu" signal "IN3")
		(16 "In7.Cu" signal "GND3")
		(18 "In8.Cu" signal "VCC")
		(20 "In9.Cu" signal "VCC1")
		(22 "In10.Cu" signal "GND4")
		(24 "In11.Cu" signal "IN4")
		(26 "In12.Cu" signal "GND5")
		(28 "In13.Cu" signal "IN5")
		(30 "In14.Cu" signal "GND6")
		(32 "In15.Cu" signal "IN6")
		(34 "In16.Cu" signal "GND7")
		(2 "B.Cu" signal "BOTTOM")
		(9 "F.Adhes" user "F.Adhesive")
		(11 "B.Adhes" user "B.Adhesive")
		(13 "F.Paste" user "Package Geometry/Pastemask Top")
		(15 "B.Paste" user "Package Geometry/Pastemask Bottom")
		(5 "F.SilkS" user "Ref Des/Silkscreen Top")
		(7 "B.SilkS" user "Ref Des/Silkscreen Bottom")
		(1 "F.Mask" user "Board Geometry/Soldermask Top")
		(3 "B.Mask" user "Board Geometry/Soldermask Bottom")
		(17 "Dwgs.User" user "User.Drawings")
		(19 "Cmts.User" user "User.Comments")
		(21 "Eco1.User" user "User.Eco1")
		(23 "Eco2.User" user "User.Eco2")
		(25 "Edge.Cuts" user "Board Geometry/Outline")
		(27 "Margin" user)
		(31 "F.CrtYd" user "Package Geometry/Place Bound Top")
		(29 "B.CrtYd" user "Package Geometry/Place Bound Bottom")
		(35 "F.Fab" user "Ref Des/Assembly Top")
		(33 "B.Fab" user "Ref Des/Assembly Bottom")
	)
	(footprint ""
		(layer "F.Cu")
		(at 61.027564 -16.220948 -90)
		(property "Reference" "R3171"
			(at 0 0 270)
			(layer "F.SilkS")
			(hide yes)
			(effects
				(font
					(size 1.27 1.27)
				)
			)
		)
		(property "Value" ""
			(at 0 0 270)
			(layer "F.Fab")
			(effects
				(font
					(size 1.27 1.27)
				)
			)
		)
		(duplicate_pad_numbers_are_jumpers no)
		(fp_line
			(start -0.7874 0.4064)
			(end -0.7874 -0.4064)
			(stroke
				(width 0.1524)
				(type default)
			)
			(layer "F.SilkS")
		)
		(fp_line
			(start 0.7874 0.4064)
			(end -0.7874 0.4064)
			(stroke
				(width 0.1524)
				(type default)
			)
			(layer "F.SilkS")
		)
		(fp_line
			(start -0.7874 -0.4064)
			(end 0.7874 -0.4064)
			(stroke
				(width 0.1524)
				(type default)
			)
			(layer "F.SilkS")
		)
		(fp_line
			(start 0.7874 -0.4064)
			(end 0.7874 0.4064)
			(stroke
				(width 0.1524)
				(type default)
			)
			(layer "F.SilkS")
		)
		(fp_line
			(start -0.67945 0.3048)
			(end -0.67945 -0.305054)
			(stroke
				(width 0.1)
				(type default)
			)
			(layer "F.Fab")
		)
		(fp_line
			(start -0.12065 0.3048)
			(end -0.67945 0.3048)
			(stroke
				(width 0.1)
				(type default)
			)
			(layer "F.Fab")
		)
		(fp_line
			(start 0.120396 0.3048)
			(end 0.120396 0.2794)
			(stroke
				(width 0.1)
				(type default)
			)
			(layer "F.Fab")
		)
		(fp_line
			(start 0.67945 0.3048)
			(end 0.120396 0.3048)
			(stroke
				(width 0.1)
				(type default)
			)
			(layer "F.Fab")
		)
		(fp_line
			(start -0.12065 0.2794)
			(end -0.12065 0.3048)
			(stroke
				(width 0.1)
				(type default)
			)
			(layer "F.Fab")
		)
		(fp_line
			(start 0.120396 0.2794)
			(end -0.12065 0.2794)
			(stroke
				(width 0.1)
				(type default)
			)
			(layer "F.Fab")
		)
		(fp_line
			(start -0.12065 -0.2794)
			(end 0.12065 -0.2794)
			(stroke
				(width 0.1)
				(type default)
			)
			(layer "F.Fab")
		)
		(fp_line
			(start 0.12065 -0.2794)
			(end 0.12065 -0.3048)
			(stroke
				(width 0.1)
				(type default)
			)
			(layer "F.Fab")
		)
		(fp_line
			(start 0.12065 -0.3048)
			(end 0.67945 -0.3048)
			(stroke
				(width 0.1)
				(type default)
			)
			(layer "F.Fab")
		)
		(fp_line
			(start 0.67945 -0.3048)
			(end 0.67945 0.3048)
			(stroke
				(width 0.1)
				(type default)
			)
			(layer "F.Fab")
		)
		(fp_line
			(start -0.67945 -0.305054)
			(end -0.12065 -0.305054)
			(stroke
				(width 0.1)
				(type default)
			)
			(layer "F.Fab")
		)
		(fp_line
			(start -0.12065 -0.305054)
			(end -0.12065 -0.2794)
			(stroke
				(width 0.1)
				(type default)
			)
			(layer "F.Fab")
		)
		(pad "1" smd circle
			(at -0.40005 0 270)
			(size 0 0)
			(layers "F.Cu" "F.Mask" "F.Paste")
			(net "OCP_V3_2_ISO_BIF2_EN")
		)
		(pad "2" smd circle
			(at 0.40005 0 270)
			(size 0 0)
			(layers "F.Cu" "F.Mask" "F.Paste")
			(net "OCP_V3_2_BIF2_R_N")
		)
	)
	(footprint ""
		(layer "F.Cu")
		(at 148.494242 -105.624884 180)
		(property "Reference" "R3298"
			(at 0 0 180)
			(layer "F.SilkS")
			(hide yes)
			(effects
				(font
					(size 1.27 1.27)
				)
			)
		)
		(property "Value" ""
			(at 0 0 180)
			(layer "F.Fab")
			(effects
				(font
					(size 1.27 1.27)
				)
			)
		)
		(duplicate_pad_numbers_are_jumpers no)
		(fp_line
			(start 0.7874 0.4064)
			(end -0.7874 0.4064)
			(stroke
				(width 0.1524)
				(type default)
			)
			(layer "F.SilkS")
		)
		(fp_line
			(start 0.7874 -0.4064)
			(end 0.7874 0.4064)
			(stroke
				(width 0.1524)
				(type default)
			)
			(layer "F.SilkS")
		)
		(fp_line
			(start -0.7874 0.4064)
			(end -0.7874 -0.4064)
			(stroke
				(width 0.1524)
				(type default)
			)
			(layer "F.SilkS")
		)
		(fp_line
			(start -0.7874 -0.4064)
			(end 0.7874 -0.4064)
			(stroke
				(width 0.1524)
				(type default)
			)
			(layer "F.SilkS")
		)
		(fp_line
			(start 0.67945 0.3048)
			(end 0.120396 0.3048)
			(stroke
				(width 0.1)
				(type default)
			)
			(layer "F.Fab")
		)
		(fp_line
			(start 0.67945 -0.3048)
			(end 0.67945 0.3048)
			(stroke
				(width 0.1)
				(type default)
			)
			(layer "F.Fab")
		)
		(fp_line
			(start 0.12065 -0.2794)
			(end 0.12065 -0.3048)
			(stroke
				(width 0.1)
				(type default)
			)
			(layer "F.Fab")
		)
		(fp_line
			(start 0.12065 -0.3048)
			(end 0.67945 -0.3048)
			(stroke
				(width 0.1)
				(type default)
			)
			(layer "F.Fab")
		)
		(fp_line
			(start 0.120396 0.3048)
			(end 0.120396 0.2794)
			(stroke
				(width 0.1)
				(type default)
			)
			(layer "F.Fab")
		)
		(fp_line
			(start 0.120396 0.2794)
			(end -0.12065 0.2794)
			(stroke
				(width 0.1)
				(type default)
			)
			(layer "F.Fab")
		)
		(fp_line
			(start -0.12065 0.3048)
			(end -0.67945 0.3048)
			(stroke
				(width 0.1)
				(type default)
			)
			(layer "F.Fab")
		)
		(fp_line
			(start -0.12065 0.2794)
			(end -0.12065 0.3048)
			(stroke
				(width 0.1)
				(type default)
			)
			(layer "F.Fab")
		)
		(fp_line
			(start -0.12065 -0.2794)
			(end 0.12065 -0.2794)
			(stroke
				(width 0.1)
				(type default)
			)
			(layer "F.Fab")
		)
		(fp_line
			(start -0.12065 -0.305054)
			(end -0.12065 -0.2794)
			(stroke
				(width 0.1)
				(type default)
			)
			(layer "F.Fab")
		)
		(fp_line
			(start -0.67945 0.3048)
			(end -0.67945 -0.305054)
			(stroke
				(width 0.1)
				(type default)
			)
			(layer "F.Fab")
		)
		(fp_line
			(start -0.67945 -0.305054)
			(end -0.12065 -0.305054)
			(stroke
				(width 0.1)
				(type default)
			)
			(layer "F.Fab")
		)
		(pad "1" smd circle
			(at -0.40005 0 180)
			(size 0 0)
			(layers "F.Cu" "F.Mask" "F.Paste")
			(net "P3V3_AUX")
		)
		(pad "2" smd circle
			(at 0.40005 0 180)
			(size 0 0)
			(layers "F.Cu" "F.Mask" "F.Paste")
			(net "HDD_ACTIVITY_BUF_N")
		)
	)
)
